(kicad_sch
	(version 20250114)
	(generator "eeschema")
	(generator_version "9.0")
	(paper "A3")
	(title_block
		(title "DDR5 testbed")
		(date "2024-05-27")
		(rev "1.1.2")
		(comment 1 "www.antmicro.com")
		(comment 2 "Antmicro Ltd.")
	)
	(text "1V1_SYS"
		(exclude_from_sim no)
		(at 83.185 181.61 0)
		(effects
			(font
				(size 2.0066 2.0066)
				(thickness 0.4013)
				(bold yes)
			)
			(justify left bottom)
		)
	)
	(text "test-board:IO_V12"
		(exclude_from_sim no)
		(at 83.185 226.695 0)
		(effects
			(font
				(size 1.27 1.27)
			)
			(justify left bottom)
		)
	)
	(text "Note:\nThe pin assignment for that connector matches\nan experimental research platform available at \nhttps://github.com/antmicro/lpddr4-test-board"
		(exclude_from_sim no)
		(at 23.495 43.18 0)
		(effects
			(font
				(size 2.4892 2.4892)
			)
			(justify left bottom)
		)
	)
	(text "SODIMM Connector"
		(exclude_from_sim no)
		(at 22.86 22.225 0)
		(effects
			(font
				(size 2.4892 2.4892)
				(thickness 0.4978)
				(bold yes)
			)
			(justify left bottom)
		)
	)
	(text "1V8_SYS"
		(exclude_from_sim no)
		(at 167.005 209.55 0)
		(effects
			(font
				(size 2.0066 2.0066)
				(thickness 0.4013)
				(bold yes)
			)
			(justify left bottom)
		)
	)
	(text "test-board:IO_U12"
		(exclude_from_sim no)
		(at 83.185 224.155 0)
		(effects
			(font
				(size 1.27 1.27)
			)
			(justify left bottom)
		)
	)
	(junction
		(at 148.59 73.66)
		(diameter 0)
		(color 0 0 0 0)
	)
	(junction
		(at 119.38 81.28)
		(diameter 0)
		(color 0 0 0 0)
	)
	(junction
		(at 119.38 71.12)
		(diameter 0)
		(color 0 0 0 0)
	)
	(junction
		(at 148.59 86.36)
		(diameter 0)
		(color 0 0 0 0)
	)
	(junction
		(at 148.59 76.2)
		(diameter 0)
		(color 0 0 0 0)
	)
	(junction
		(at 148.59 78.74)
		(diameter 0)
		(color 0 0 0 0)
	)
	(junction
		(at 152.4 213.36)
		(diameter 0)
		(color 0 0 0 0)
	)
	(junction
		(at 148.59 68.58)
		(diameter 0)
		(color 0 0 0 0)
	)
	(junction
		(at 148.59 101.6)
		(diameter 0)
		(color 0 0 0 0)
	)
	(junction
		(at 119.38 68.58)
		(diameter 0)
		(color 0 0 0 0)
	)
	(junction
		(at 119.38 66.04)
		(diameter 0)
		(color 0 0 0 0)
	)
	(junction
		(at 152.4 215.9)
		(diameter 0)
		(color 0 0 0 0)
	)
	(junction
		(at 113.665 190.5)
		(diameter 0)
		(color 0 0 0 0)
	)
	(junction
		(at 148.59 119.38)
		(diameter 0)
		(color 0 0 0 0)
	)
	(junction
		(at 148.59 96.52)
		(diameter 0)
		(color 0 0 0 0)
	)
	(junction
		(at 148.59 116.84)
		(diameter 0)
		(color 0 0 0 0)
	)
	(junction
		(at 148.59 111.76)
		(diameter 0)
		(color 0 0 0 0)
	)
	(junction
		(at 119.38 106.68)
		(diameter 0)
		(color 0 0 0 0)
	)
	(junction
		(at 265.43 152.4)
		(diameter 0)
		(color 0 0 0 0)
	)
	(junction
		(at 265.43 165.1)
		(diameter 0)
		(color 0 0 0 0)
	)
	(junction
		(at 265.43 132.08)
		(diameter 0)
		(color 0 0 0 0)
	)
	(junction
		(at 152.4 210.82)
		(diameter 0)
		(color 0 0 0 0)
	)
	(junction
		(at 148.59 88.9)
		(diameter 0)
		(color 0 0 0 0)
	)
	(junction
		(at 119.38 114.3)
		(diameter 0)
		(color 0 0 0 0)
	)
	(junction
		(at 119.38 104.14)
		(diameter 0)
		(color 0 0 0 0)
	)
	(junction
		(at 113.665 185.42)
		(diameter 0)
		(color 0 0 0 0)
	)
	(junction
		(at 148.59 71.12)
		(diameter 0)
		(color 0 0 0 0)
	)
	(junction
		(at 148.59 104.14)
		(diameter 0)
		(color 0 0 0 0)
	)
	(junction
		(at 113.665 187.96)
		(diameter 0)
		(color 0 0 0 0)
	)
	(junction
		(at 119.38 121.92)
		(diameter 0)
		(color 0 0 0 0)
	)
	(junction
		(at 113.665 182.88)
		(diameter 0)
		(color 0 0 0 0)
	)
	(junction
		(at 239.395 124.46)
		(diameter 0)
		(color 0 0 0 0)
	)
	(junction
		(at 148.59 106.68)
		(diameter 0)
		(color 0 0 0 0)
	)
	(junction
		(at 148.59 83.82)
		(diameter 0)
		(color 0 0 0 0)
	)
	(junction
		(at 148.59 114.3)
		(diameter 0)
		(color 0 0 0 0)
	)
	(junction
		(at 119.38 119.38)
		(diameter 0)
		(color 0 0 0 0)
	)
	(junction
		(at 148.59 91.44)
		(diameter 0)
		(color 0 0 0 0)
	)
	(junction
		(at 119.38 96.52)
		(diameter 0)
		(color 0 0 0 0)
	)
	(junction
		(at 239.395 147.32)
		(diameter 0)
		(color 0 0 0 0)
	)
	(junction
		(at 239.395 167.64)
		(diameter 0)
		(color 0 0 0 0)
	)
	(junction
		(at 148.59 81.28)
		(diameter 0)
		(color 0 0 0 0)
	)
	(junction
		(at 119.38 86.36)
		(diameter 0)
		(color 0 0 0 0)
	)
	(junction
		(at 119.38 124.46)
		(diameter 0)
		(color 0 0 0 0)
	)
	(junction
		(at 148.59 124.46)
		(diameter 0)
		(color 0 0 0 0)
	)
	(junction
		(at 119.38 83.82)
		(diameter 0)
		(color 0 0 0 0)
	)
	(junction
		(at 119.38 91.44)
		(diameter 0)
		(color 0 0 0 0)
	)
	(junction
		(at 119.38 76.2)
		(diameter 0)
		(color 0 0 0 0)
	)
	(junction
		(at 148.59 66.04)
		(diameter 0)
		(color 0 0 0 0)
	)
	(junction
		(at 119.38 101.6)
		(diameter 0)
		(color 0 0 0 0)
	)
	(junction
		(at 119.38 99.06)
		(diameter 0)
		(color 0 0 0 0)
	)
	(junction
		(at 148.59 93.98)
		(diameter 0)
		(color 0 0 0 0)
	)
	(junction
		(at 119.38 88.9)
		(diameter 0)
		(color 0 0 0 0)
	)
	(junction
		(at 119.38 73.66)
		(diameter 0)
		(color 0 0 0 0)
	)
	(junction
		(at 119.38 116.84)
		(diameter 0)
		(color 0 0 0 0)
	)
	(junction
		(at 113.665 193.04)
		(diameter 0)
		(color 0 0 0 0)
	)
	(junction
		(at 265.43 111.76)
		(diameter 0)
		(color 0 0 0 0)
	)
	(junction
		(at 119.38 111.76)
		(diameter 0)
		(color 0 0 0 0)
	)
	(junction
		(at 113.665 195.58)
		(diameter 0)
		(color 0 0 0 0)
	)
	(junction
		(at 119.38 78.74)
		(diameter 0)
		(color 0 0 0 0)
	)
	(junction
		(at 119.38 93.98)
		(diameter 0)
		(color 0 0 0 0)
	)
	(junction
		(at 152.4 208.28)
		(diameter 0)
		(color 0 0 0 0)
	)
	(junction
		(at 148.59 109.22)
		(diameter 0)
		(color 0 0 0 0)
	)
	(junction
		(at 148.59 99.06)
		(diameter 0)
		(color 0 0 0 0)
	)
	(junction
		(at 113.665 180.34)
		(diameter 0)
		(color 0 0 0 0)
	)
	(junction
		(at 148.59 121.92)
		(diameter 0)
		(color 0 0 0 0)
	)
	(junction
		(at 119.38 109.22)
		(diameter 0)
		(color 0 0 0 0)
	)
	(no_connect
		(at 122.555 154.94)
	)
	(no_connect
		(at 264.16 139.7)
	)
	(no_connect
		(at 241.3 170.18)
	)
	(no_connect
		(at 122.555 137.16)
	)
	(no_connect
		(at 241.3 68.58)
	)
	(no_connect
		(at 264.16 226.06)
	)
	(no_connect
		(at 241.3 195.58)
	)
	(no_connect
		(at 145.415 160.02)
	)
	(no_connect
		(at 122.555 177.8)
	)
	(no_connect
		(at 264.16 228.6)
	)
	(no_connect
		(at 122.555 147.32)
	)
	(no_connect
		(at 145.415 162.56)
	)
	(no_connect
		(at 241.3 66.04)
	)
	(no_connect
		(at 264.16 185.42)
	)
	(no_connect
		(at 122.555 152.4)
	)
	(no_connect
		(at 264.16 203.2)
	)
	(no_connect
		(at 241.3 187.96)
	)
	(no_connect
		(at 122.555 200.66)
	)
	(no_connect
		(at 264.16 205.74)
	)
	(no_connect
		(at 145.415 165.1)
	)
	(no_connect
		(at 122.555 127)
	)
	(no_connect
		(at 264.16 218.44)
	)
	(no_connect
		(at 145.415 127)
	)
	(no_connect
		(at 264.16 172.72)
	)
	(no_connect
		(at 122.555 208.28)
	)
	(no_connect
		(at 145.415 152.4)
	)
	(no_connect
		(at 145.415 177.8)
	)
	(no_connect
		(at 145.415 205.74)
	)
	(no_connect
		(at 145.415 139.7)
	)
	(no_connect
		(at 264.16 223.52)
	)
	(no_connect
		(at 241.3 76.2)
	)
	(no_connect
		(at 122.555 149.86)
	)
	(no_connect
		(at 264.16 208.28)
	)
	(no_connect
		(at 241.3 215.9)
	)
	(no_connect
		(at 145.415 154.94)
	)
	(no_connect
		(at 241.3 182.88)
	)
	(no_connect
		(at 145.415 198.12)
	)
	(no_connect
		(at 241.3 203.2)
	)
	(no_connect
		(at 122.555 162.56)
	)
	(no_connect
		(at 145.415 180.34)
	)
	(no_connect
		(at 122.555 167.64)
	)
	(no_connect
		(at 145.415 195.58)
	)
	(no_connect
		(at 241.3 205.74)
	)
	(no_connect
		(at 241.3 185.42)
	)
	(no_connect
		(at 122.555 205.74)
	)
	(no_connect
		(at 241.3 210.82)
	)
	(no_connect
		(at 264.16 119.38)
	)
	(no_connect
		(at 264.16 200.66)
	)
	(no_connect
		(at 122.555 142.24)
	)
	(no_connect
		(at 264.16 213.36)
	)
	(no_connect
		(at 241.3 200.66)
	)
	(no_connect
		(at 241.3 101.6)
	)
	(no_connect
		(at 241.3 228.6)
	)
	(no_connect
		(at 122.555 157.48)
	)
	(no_connect
		(at 264.16 78.74)
	)
	(no_connect
		(at 264.16 76.2)
	)
	(no_connect
		(at 241.3 213.36)
	)
	(no_connect
		(at 145.415 172.72)
	)
	(no_connect
		(at 264.16 88.9)
	)
	(no_connect
		(at 122.555 144.78)
	)
	(no_connect
		(at 241.3 86.36)
	)
	(no_connect
		(at 241.3 71.12)
	)
	(no_connect
		(at 145.415 170.18)
	)
	(no_connect
		(at 145.415 134.62)
	)
	(no_connect
		(at 122.555 132.08)
	)
	(no_connect
		(at 145.415 149.86)
	)
	(no_connect
		(at 264.16 73.66)
	)
	(no_connect
		(at 122.555 129.54)
	)
	(no_connect
		(at 264.16 71.12)
	)
	(no_connect
		(at 241.3 226.06)
	)
	(no_connect
		(at 264.16 187.96)
	)
	(no_connect
		(at 264.16 195.58)
	)
	(no_connect
		(at 122.555 170.18)
	)
	(no_connect
		(at 122.555 172.72)
	)
	(no_connect
		(at 145.415 142.24)
	)
	(no_connect
		(at 122.555 165.1)
	)
	(no_connect
		(at 264.16 193.04)
	)
	(no_connect
		(at 241.3 218.44)
	)
	(no_connect
		(at 264.16 220.98)
	)
	(no_connect
		(at 122.555 139.7)
	)
	(no_connect
		(at 145.415 187.96)
	)
	(no_connect
		(at 264.16 180.34)
	)
	(no_connect
		(at 264.16 83.82)
	)
	(no_connect
		(at 264.16 121.92)
	)
	(no_connect
		(at 145.415 220.98)
	)
	(no_connect
		(at 264.16 215.9)
	)
	(no_connect
		(at 145.415 182.88)
	)
	(no_connect
		(at 241.3 180.34)
	)
	(no_connect
		(at 122.555 134.62)
	)
	(no_connect
		(at 122.555 220.98)
	)
	(no_connect
		(at 145.415 144.78)
	)
	(no_connect
		(at 264.16 190.5)
	)
	(no_connect
		(at 241.3 172.72)
	)
	(no_connect
		(at 264.16 182.88)
	)
	(no_connect
		(at 122.555 215.9)
	)
	(no_connect
		(at 241.3 177.8)
	)
	(no_connect
		(at 122.555 175.26)
	)
	(no_connect
		(at 241.3 208.28)
	)
	(no_connect
		(at 264.16 162.56)
	)
	(no_connect
		(at 241.3 78.74)
	)
	(no_connect
		(at 145.415 203.2)
	)
	(no_connect
		(at 264.16 86.36)
	)
	(no_connect
		(at 264.16 68.58)
	)
	(no_connect
		(at 241.3 96.52)
	)
	(no_connect
		(at 264.16 198.12)
	)
	(no_connect
		(at 145.415 226.06)
	)
	(no_connect
		(at 241.3 81.28)
	)
	(no_connect
		(at 264.16 91.44)
	)
	(no_connect
		(at 241.3 198.12)
	)
	(no_connect
		(at 145.415 193.04)
	)
	(no_connect
		(at 145.415 147.32)
	)
	(no_connect
		(at 122.555 213.36)
	)
	(no_connect
		(at 145.415 167.64)
	)
	(no_connect
		(at 241.3 193.04)
	)
	(no_connect
		(at 241.3 175.26)
	)
	(no_connect
		(at 264.16 116.84)
	)
	(no_connect
		(at 241.3 91.44)
	)
	(no_connect
		(at 241.3 93.98)
	)
	(no_connect
		(at 145.415 190.5)
	)
	(no_connect
		(at 241.3 83.82)
	)
	(no_connect
		(at 264.16 66.04)
	)
	(no_connect
		(at 241.3 220.98)
	)
	(no_connect
		(at 122.555 203.2)
	)
	(no_connect
		(at 241.3 223.52)
	)
	(no_connect
		(at 145.415 185.42)
	)
	(no_connect
		(at 264.16 114.3)
	)
	(no_connect
		(at 264.16 177.8)
	)
	(no_connect
		(at 264.16 210.82)
	)
	(no_connect
		(at 145.415 223.52)
	)
	(no_connect
		(at 241.3 190.5)
	)
	(no_connect
		(at 145.415 137.16)
	)
	(no_connect
		(at 241.3 73.66)
	)
	(no_connect
		(at 264.16 170.18)
	)
	(no_connect
		(at 264.16 175.26)
	)
	(no_connect
		(at 145.415 132.08)
	)
	(no_connect
		(at 145.415 200.66)
	)
	(no_connect
		(at 241.3 88.9)
	)
	(no_connect
		(at 122.555 210.82)
	)
	(no_connect
		(at 264.16 81.28)
	)
	(no_connect
		(at 241.3 99.06)
	)
	(no_connect
		(at 145.415 175.26)
	)
	(no_connect
		(at 122.555 160.02)
	)
	(no_connect
		(at 145.415 157.48)
	)
	(no_connect
		(at 122.555 218.44)
	)
	(no_connect
		(at 264.16 167.64)
	)
	(no_connect
		(at 264.16 137.16)
	)
	(no_connect
		(at 145.415 129.54)
	)
	(no_connect
		(at 264.16 154.94)
	)
	(wire
		(pts
			(xy 239.395 104.14) (xy 239.395 124.46)
		)
		(stroke
			(width 0)
			(type default)
		)
	)
	(wire
		(pts
			(xy 145.415 66.04) (xy 148.59 66.04)
		)
		(stroke
			(width 0)
			(type default)
		)
	)
	(wire
		(pts
			(xy 145.415 106.68) (xy 148.59 106.68)
		)
		(stroke
			(width 0)
			(type default)
		)
	)
	(wire
		(pts
			(xy 122.555 71.12) (xy 119.38 71.12)
		)
		(stroke
			(width 0)
			(type default)
		)
	)
	(wire
		(pts
			(xy 122.555 91.44) (xy 119.38 91.44)
		)
		(stroke
			(width 0)
			(type default)
		)
	)
	(wire
		(pts
			(xy 148.59 91.44) (xy 148.59 93.98)
		)
		(stroke
			(width 0)
			(type default)
		)
	)
	(wire
		(pts
			(xy 119.38 88.9) (xy 119.38 91.44)
		)
		(stroke
			(width 0)
			(type default)
		)
	)
	(wire
		(pts
			(xy 119.38 76.2) (xy 119.38 78.74)
		)
		(stroke
			(width 0)
			(type default)
		)
	)
	(wire
		(pts
			(xy 241.3 109.22) (xy 225.425 109.22)
		)
		(stroke
			(width 0)
			(type default)
		)
	)
	(wire
		(pts
			(xy 122.555 86.36) (xy 119.38 86.36)
		)
		(stroke
			(width 0)
			(type default)
		)
	)
	(wire
		(pts
			(xy 148.59 121.92) (xy 148.59 124.46)
		)
		(stroke
			(width 0)
			(type default)
		)
	)
	(wire
		(pts
			(xy 152.4 208.28) (xy 157.48 208.28)
		)
		(stroke
			(width 0)
			(type default)
		)
	)
	(wire
		(pts
			(xy 145.415 99.06) (xy 148.59 99.06)
		)
		(stroke
			(width 0)
			(type default)
		)
	)
	(wire
		(pts
			(xy 113.665 185.42) (xy 122.555 185.42)
		)
		(stroke
			(width 0)
			(type default)
		)
	)
	(wire
		(pts
			(xy 107.315 226.06) (xy 122.555 226.06)
		)
		(stroke
			(width 0)
			(type default)
		)
	)
	(wire
		(pts
			(xy 264.16 124.46) (xy 281.305 124.46)
		)
		(stroke
			(width 0)
			(type default)
		)
	)
	(wire
		(pts
			(xy 241.3 147.32) (xy 239.395 147.32)
		)
		(stroke
			(width 0)
			(type default)
		)
	)
	(wire
		(pts
			(xy 122.555 76.2) (xy 119.38 76.2)
		)
		(stroke
			(width 0)
			(type default)
		)
	)
	(wire
		(pts
			(xy 241.3 142.24) (xy 225.425 142.24)
		)
		(stroke
			(width 0)
			(type default)
		)
	)
	(wire
		(pts
			(xy 145.415 109.22) (xy 148.59 109.22)
		)
		(stroke
			(width 0)
			(type default)
		)
	)
	(wire
		(pts
			(xy 119.38 91.44) (xy 119.38 93.98)
		)
		(stroke
			(width 0)
			(type default)
		)
	)
	(wire
		(pts
			(xy 145.415 73.66) (xy 148.59 73.66)
		)
		(stroke
			(width 0)
			(type default)
		)
	)
	(wire
		(pts
			(xy 148.59 86.36) (xy 148.59 88.9)
		)
		(stroke
			(width 0)
			(type default)
		)
	)
	(wire
		(pts
			(xy 122.555 195.58) (xy 113.665 195.58)
		)
		(stroke
			(width 0)
			(type default)
		)
	)
	(wire
		(pts
			(xy 264.16 106.68) (xy 281.305 106.68)
		)
		(stroke
			(width 0)
			(type default)
		)
	)
	(wire
		(pts
			(xy 265.43 93.98) (xy 265.43 111.76)
		)
		(stroke
			(width 0)
			(type default)
		)
	)
	(wire
		(pts
			(xy 241.3 137.16) (xy 225.425 137.16)
		)
		(stroke
			(width 0)
			(type default)
		)
	)
	(wire
		(pts
			(xy 119.38 63.5) (xy 119.38 66.04)
		)
		(stroke
			(width 0)
			(type default)
		)
	)
	(wire
		(pts
			(xy 122.555 121.92) (xy 119.38 121.92)
		)
		(stroke
			(width 0)
			(type default)
		)
	)
	(wire
		(pts
			(xy 148.59 68.58) (xy 148.59 71.12)
		)
		(stroke
			(width 0)
			(type default)
		)
	)
	(wire
		(pts
			(xy 145.415 88.9) (xy 148.59 88.9)
		)
		(stroke
			(width 0)
			(type default)
		)
	)
	(wire
		(pts
			(xy 148.59 111.76) (xy 148.59 114.3)
		)
		(stroke
			(width 0)
			(type default)
		)
	)
	(wire
		(pts
			(xy 264.16 134.62) (xy 281.305 134.62)
		)
		(stroke
			(width 0)
			(type default)
		)
	)
	(wire
		(pts
			(xy 145.415 63.5) (xy 148.59 63.5)
		)
		(stroke
			(width 0)
			(type default)
		)
	)
	(wire
		(pts
			(xy 113.665 195.58) (xy 113.665 193.04)
		)
		(stroke
			(width 0)
			(type default)
		)
	)
	(wire
		(pts
			(xy 148.59 63.5) (xy 148.59 66.04)
		)
		(stroke
			(width 0)
			(type default)
		)
	)
	(wire
		(pts
			(xy 122.555 99.06) (xy 119.38 99.06)
		)
		(stroke
			(width 0)
			(type default)
		)
	)
	(wire
		(pts
			(xy 122.555 182.88) (xy 113.665 182.88)
		)
		(stroke
			(width 0)
			(type default)
		)
	)
	(wire
		(pts
			(xy 264.16 149.86) (xy 281.305 149.86)
		)
		(stroke
			(width 0)
			(type default)
		)
	)
	(wire
		(pts
			(xy 265.43 111.76) (xy 265.43 132.08)
		)
		(stroke
			(width 0)
			(type default)
		)
	)
	(wire
		(pts
			(xy 119.38 116.84) (xy 119.38 119.38)
		)
		(stroke
			(width 0)
			(type default)
		)
	)
	(wire
		(pts
			(xy 148.59 119.38) (xy 148.59 121.92)
		)
		(stroke
			(width 0)
			(type default)
		)
	)
	(wire
		(pts
			(xy 113.665 190.5) (xy 113.665 187.96)
		)
		(stroke
			(width 0)
			(type default)
		)
	)
	(wire
		(pts
			(xy 113.665 182.88) (xy 113.665 180.34)
		)
		(stroke
			(width 0)
			(type default)
		)
	)
	(wire
		(pts
			(xy 122.555 73.66) (xy 119.38 73.66)
		)
		(stroke
			(width 0)
			(type default)
		)
	)
	(wire
		(pts
			(xy 241.3 154.94) (xy 225.425 154.94)
		)
		(stroke
			(width 0)
			(type default)
		)
	)
	(wire
		(pts
			(xy 145.415 210.82) (xy 152.4 210.82)
		)
		(stroke
			(width 0)
			(type default)
		)
	)
	(wire
		(pts
			(xy 241.3 129.54) (xy 225.425 129.54)
		)
		(stroke
			(width 0)
			(type default)
		)
	)
	(wire
		(pts
			(xy 119.38 81.28) (xy 119.38 83.82)
		)
		(stroke
			(width 0)
			(type default)
		)
	)
	(wire
		(pts
			(xy 113.665 187.96) (xy 113.665 185.42)
		)
		(stroke
			(width 0)
			(type default)
		)
	)
	(wire
		(pts
			(xy 122.555 187.96) (xy 113.665 187.96)
		)
		(stroke
			(width 0)
			(type default)
		)
	)
	(wire
		(pts
			(xy 145.415 208.28) (xy 152.4 208.28)
		)
		(stroke
			(width 0)
			(type default)
		)
	)
	(wire
		(pts
			(xy 119.38 111.76) (xy 119.38 114.3)
		)
		(stroke
			(width 0)
			(type default)
		)
	)
	(wire
		(pts
			(xy 122.555 63.5) (xy 119.38 63.5)
		)
		(stroke
			(width 0)
			(type default)
		)
	)
	(wire
		(pts
			(xy 145.415 93.98) (xy 148.59 93.98)
		)
		(stroke
			(width 0)
			(type default)
		)
	)
	(wire
		(pts
			(xy 148.59 78.74) (xy 148.59 81.28)
		)
		(stroke
			(width 0)
			(type default)
		)
	)
	(wire
		(pts
			(xy 122.555 78.74) (xy 119.38 78.74)
		)
		(stroke
			(width 0)
			(type default)
		)
	)
	(wire
		(pts
			(xy 122.555 93.98) (xy 119.38 93.98)
		)
		(stroke
			(width 0)
			(type default)
		)
	)
	(wire
		(pts
			(xy 148.59 99.06) (xy 148.59 101.6)
		)
		(stroke
			(width 0)
			(type default)
		)
	)
	(wire
		(pts
			(xy 148.59 83.82) (xy 148.59 86.36)
		)
		(stroke
			(width 0)
			(type default)
		)
	)
	(wire
		(pts
			(xy 152.4 218.44) (xy 152.4 215.9)
		)
		(stroke
			(width 0)
			(type default)
		)
	)
	(wire
		(pts
			(xy 119.38 86.36) (xy 119.38 88.9)
		)
		(stroke
			(width 0)
			(type default)
		)
	)
	(wire
		(pts
			(xy 145.415 68.58) (xy 148.59 68.58)
		)
		(stroke
			(width 0)
			(type default)
		)
	)
	(wire
		(pts
			(xy 152.4 215.9) (xy 152.4 213.36)
		)
		(stroke
			(width 0)
			(type default)
		)
	)
	(wire
		(pts
			(xy 119.38 78.74) (xy 119.38 81.28)
		)
		(stroke
			(width 0)
			(type default)
		)
	)
	(wire
		(pts
			(xy 122.555 106.68) (xy 119.38 106.68)
		)
		(stroke
			(width 0)
			(type default)
		)
	)
	(wire
		(pts
			(xy 122.555 96.52) (xy 119.38 96.52)
		)
		(stroke
			(width 0)
			(type default)
		)
	)
	(wire
		(pts
			(xy 148.59 101.6) (xy 148.59 104.14)
		)
		(stroke
			(width 0)
			(type default)
		)
	)
	(wire
		(pts
			(xy 241.3 132.08) (xy 225.425 132.08)
		)
		(stroke
			(width 0)
			(type default)
		)
	)
	(wire
		(pts
			(xy 264.16 93.98) (xy 265.43 93.98)
		)
		(stroke
			(width 0)
			(type default)
		)
	)
	(wire
		(pts
			(xy 119.38 73.66) (xy 119.38 76.2)
		)
		(stroke
			(width 0)
			(type default)
		)
	)
	(wire
		(pts
			(xy 241.3 104.14) (xy 239.395 104.14)
		)
		(stroke
			(width 0)
			(type default)
		)
	)
	(wire
		(pts
			(xy 122.555 104.14) (xy 119.38 104.14)
		)
		(stroke
			(width 0)
			(type default)
		)
	)
	(wire
		(pts
			(xy 264.16 96.52) (xy 281.305 96.52)
		)
		(stroke
			(width 0)
			(type default)
		)
	)
	(wire
		(pts
			(xy 264.16 99.06) (xy 281.305 99.06)
		)
		(stroke
			(width 0)
			(type default)
		)
	)
	(wire
		(pts
			(xy 264.16 129.54) (xy 281.305 129.54)
		)
		(stroke
			(width 0)
			(type default)
		)
	)
	(wire
		(pts
			(xy 122.555 119.38) (xy 119.38 119.38)
		)
		(stroke
			(width 0)
			(type default)
		)
	)
	(wire
		(pts
			(xy 241.3 119.38) (xy 225.425 119.38)
		)
		(stroke
			(width 0)
			(type default)
		)
	)
	(wire
		(pts
			(xy 119.38 121.92) (xy 119.38 124.46)
		)
		(stroke
			(width 0)
			(type default)
		)
	)
	(wire
		(pts
			(xy 122.555 180.34) (xy 113.665 180.34)
		)
		(stroke
			(width 0)
			(type default)
		)
	)
	(wire
		(pts
			(xy 145.415 104.14) (xy 148.59 104.14)
		)
		(stroke
			(width 0)
			(type default)
		)
	)
	(wire
		(pts
			(xy 119.38 96.52) (xy 119.38 99.06)
		)
		(stroke
			(width 0)
			(type default)
		)
	)
	(wire
		(pts
			(xy 241.3 149.86) (xy 225.425 149.86)
		)
		(stroke
			(width 0)
			(type default)
		)
	)
	(wire
		(pts
			(xy 265.43 152.4) (xy 265.43 165.1)
		)
		(stroke
			(width 0)
			(type default)
		)
	)
	(wire
		(pts
			(xy 152.4 213.36) (xy 152.4 210.82)
		)
		(stroke
			(width 0)
			(type default)
		)
	)
	(wire
		(pts
			(xy 241.3 139.7) (xy 225.425 139.7)
		)
		(stroke
			(width 0)
			(type default)
		)
	)
	(wire
		(pts
			(xy 122.555 66.04) (xy 119.38 66.04)
		)
		(stroke
			(width 0)
			(type default)
		)
	)
	(wire
		(pts
			(xy 113.665 193.04) (xy 113.665 190.5)
		)
		(stroke
			(width 0)
			(type default)
		)
	)
	(wire
		(pts
			(xy 122.555 198.12) (xy 113.665 198.12)
		)
		(stroke
			(width 0)
			(type default)
		)
	)
	(wire
		(pts
			(xy 145.415 81.28) (xy 148.59 81.28)
		)
		(stroke
			(width 0)
			(type default)
		)
	)
	(wire
		(pts
			(xy 145.415 83.82) (xy 148.59 83.82)
		)
		(stroke
			(width 0)
			(type default)
		)
	)
	(wire
		(pts
			(xy 145.415 101.6) (xy 148.59 101.6)
		)
		(stroke
			(width 0)
			(type default)
		)
	)
	(wire
		(pts
			(xy 241.3 167.64) (xy 239.395 167.64)
		)
		(stroke
			(width 0)
			(type default)
		)
	)
	(wire
		(pts
			(xy 264.16 111.76) (xy 265.43 111.76)
		)
		(stroke
			(width 0)
			(type default)
		)
	)
	(wire
		(pts
			(xy 239.395 167.64) (xy 239.395 231.775)
		)
		(stroke
			(width 0)
			(type default)
		)
	)
	(wire
		(pts
			(xy 264.16 142.24) (xy 281.305 142.24)
		)
		(stroke
			(width 0)
			(type default)
		)
	)
	(wire
		(pts
			(xy 122.555 88.9) (xy 119.38 88.9)
		)
		(stroke
			(width 0)
			(type default)
		)
	)
	(wire
		(pts
			(xy 148.59 96.52) (xy 148.59 99.06)
		)
		(stroke
			(width 0)
			(type default)
		)
	)
	(wire
		(pts
			(xy 122.555 101.6) (xy 119.38 101.6)
		)
		(stroke
			(width 0)
			(type default)
		)
	)
	(wire
		(pts
			(xy 145.415 76.2) (xy 148.59 76.2)
		)
		(stroke
			(width 0)
			(type default)
		)
	)
	(wire
		(pts
			(xy 145.415 71.12) (xy 148.59 71.12)
		)
		(stroke
			(width 0)
			(type default)
		)
	)
	(wire
		(pts
			(xy 264.16 152.4) (xy 265.43 152.4)
		)
		(stroke
			(width 0)
			(type default)
		)
	)
	(wire
		(pts
			(xy 241.3 152.4) (xy 225.425 152.4)
		)
		(stroke
			(width 0)
			(type default)
		)
	)
	(wire
		(pts
			(xy 122.555 68.58) (xy 119.38 68.58)
		)
		(stroke
			(width 0)
			(type default)
		)
	)
	(wire
		(pts
			(xy 241.3 157.48) (xy 225.425 157.48)
		)
		(stroke
			(width 0)
			(type default)
		)
	)
	(wire
		(pts
			(xy 113.665 198.12) (xy 113.665 195.58)
		)
		(stroke
			(width 0)
			(type default)
		)
	)
	(wire
		(pts
			(xy 145.415 111.76) (xy 148.59 111.76)
		)
		(stroke
			(width 0)
			(type default)
		)
	)
	(wire
		(pts
			(xy 241.3 127) (xy 225.425 127)
		)
		(stroke
			(width 0)
			(type default)
		)
	)
	(wire
		(pts
			(xy 145.415 218.44) (xy 152.4 218.44)
		)
		(stroke
			(width 0)
			(type default)
		)
	)
	(wire
		(pts
			(xy 148.59 73.66) (xy 148.59 76.2)
		)
		(stroke
			(width 0)
			(type default)
		)
	)
	(wire
		(pts
			(xy 264.16 101.6) (xy 281.305 101.6)
		)
		(stroke
			(width 0)
			(type default)
		)
	)
	(wire
		(pts
			(xy 148.59 81.28) (xy 148.59 83.82)
		)
		(stroke
			(width 0)
			(type default)
		)
	)
	(wire
		(pts
			(xy 122.555 111.76) (xy 119.38 111.76)
		)
		(stroke
			(width 0)
			(type default)
		)
	)
	(wire
		(pts
			(xy 148.59 93.98) (xy 148.59 96.52)
		)
		(stroke
			(width 0)
			(type default)
		)
	)
	(wire
		(pts
			(xy 148.59 71.12) (xy 148.59 73.66)
		)
		(stroke
			(width 0)
			(type default)
		)
	)
	(wire
		(pts
			(xy 119.38 119.38) (xy 119.38 121.92)
		)
		(stroke
			(width 0)
			(type default)
		)
	)
	(wire
		(pts
			(xy 119.38 114.3) (xy 119.38 116.84)
		)
		(stroke
			(width 0)
			(type default)
		)
	)
	(wire
		(pts
			(xy 145.415 119.38) (xy 148.59 119.38)
		)
		(stroke
			(width 0)
			(type default)
		)
	)
	(wire
		(pts
			(xy 122.555 109.22) (xy 119.38 109.22)
		)
		(stroke
			(width 0)
			(type default)
		)
	)
	(wire
		(pts
			(xy 264.16 147.32) (xy 281.305 147.32)
		)
		(stroke
			(width 0)
			(type default)
		)
	)
	(wire
		(pts
			(xy 113.665 180.34) (xy 106.045 180.34)
		)
		(stroke
			(width 0)
			(type default)
		)
	)
	(wire
		(pts
			(xy 119.38 66.04) (xy 119.38 68.58)
		)
		(stroke
			(width 0)
			(type default)
		)
	)
	(wire
		(pts
			(xy 145.415 116.84) (xy 148.59 116.84)
		)
		(stroke
			(width 0)
			(type default)
		)
	)
	(wire
		(pts
			(xy 119.38 71.12) (xy 119.38 73.66)
		)
		(stroke
			(width 0)
			(type default)
		)
	)
	(wire
		(pts
			(xy 241.3 162.56) (xy 225.425 162.56)
		)
		(stroke
			(width 0)
			(type default)
		)
	)
	(wire
		(pts
			(xy 145.415 121.92) (xy 148.59 121.92)
		)
		(stroke
			(width 0)
			(type default)
		)
	)
	(wire
		(pts
			(xy 119.38 68.58) (xy 119.38 71.12)
		)
		(stroke
			(width 0)
			(type default)
		)
	)
	(wire
		(pts
			(xy 122.555 83.82) (xy 119.38 83.82)
		)
		(stroke
			(width 0)
			(type default)
		)
	)
	(wire
		(pts
			(xy 264.16 104.14) (xy 281.305 104.14)
		)
		(stroke
			(width 0)
			(type default)
		)
	)
	(wire
		(pts
			(xy 265.43 165.1) (xy 265.43 231.775)
		)
		(stroke
			(width 0)
			(type default)
		)
	)
	(wire
		(pts
			(xy 264.16 127) (xy 281.305 127)
		)
		(stroke
			(width 0)
			(type default)
		)
	)
	(wire
		(pts
			(xy 148.59 76.2) (xy 148.59 78.74)
		)
		(stroke
			(width 0)
			(type default)
		)
	)
	(wire
		(pts
			(xy 241.3 144.78) (xy 225.425 144.78)
		)
		(stroke
			(width 0)
			(type default)
		)
	)
	(wire
		(pts
			(xy 148.59 124.46) (xy 148.59 231.775)
		)
		(stroke
			(width 0)
			(type default)
		)
	)
	(wire
		(pts
			(xy 241.3 124.46) (xy 239.395 124.46)
		)
		(stroke
			(width 0)
			(type default)
		)
	)
	(wire
		(pts
			(xy 148.59 104.14) (xy 148.59 106.68)
		)
		(stroke
			(width 0)
			(type default)
		)
	)
	(wire
		(pts
			(xy 122.555 124.46) (xy 119.38 124.46)
		)
		(stroke
			(width 0)
			(type default)
		)
	)
	(wire
		(pts
			(xy 264.16 165.1) (xy 265.43 165.1)
		)
		(stroke
			(width 0)
			(type default)
		)
	)
	(wire
		(pts
			(xy 264.16 132.08) (xy 265.43 132.08)
		)
		(stroke
			(width 0)
			(type default)
		)
	)
	(wire
		(pts
			(xy 119.38 101.6) (xy 119.38 104.14)
		)
		(stroke
			(width 0)
			(type default)
		)
	)
	(wire
		(pts
			(xy 148.59 88.9) (xy 148.59 91.44)
		)
		(stroke
			(width 0)
			(type default)
		)
	)
	(wire
		(pts
			(xy 145.415 114.3) (xy 148.59 114.3)
		)
		(stroke
			(width 0)
			(type default)
		)
	)
	(wire
		(pts
			(xy 241.3 116.84) (xy 225.425 116.84)
		)
		(stroke
			(width 0)
			(type default)
		)
	)
	(wire
		(pts
			(xy 264.16 109.22) (xy 281.305 109.22)
		)
		(stroke
			(width 0)
			(type default)
		)
	)
	(wire
		(pts
			(xy 241.3 134.62) (xy 225.425 134.62)
		)
		(stroke
			(width 0)
			(type default)
		)
	)
	(wire
		(pts
			(xy 119.38 99.06) (xy 119.38 101.6)
		)
		(stroke
			(width 0)
			(type default)
		)
	)
	(wire
		(pts
			(xy 241.3 121.92) (xy 225.425 121.92)
		)
		(stroke
			(width 0)
			(type default)
		)
	)
	(wire
		(pts
			(xy 122.555 116.84) (xy 119.38 116.84)
		)
		(stroke
			(width 0)
			(type default)
		)
	)
	(wire
		(pts
			(xy 152.4 210.82) (xy 152.4 208.28)
		)
		(stroke
			(width 0)
			(type default)
		)
	)
	(wire
		(pts
			(xy 239.395 124.46) (xy 239.395 147.32)
		)
		(stroke
			(width 0)
			(type default)
		)
	)
	(wire
		(pts
			(xy 119.38 106.68) (xy 119.38 109.22)
		)
		(stroke
			(width 0)
			(type default)
		)
	)
	(wire
		(pts
			(xy 145.415 124.46) (xy 148.59 124.46)
		)
		(stroke
			(width 0)
			(type default)
		)
	)
	(wire
		(pts
			(xy 107.315 223.52) (xy 122.555 223.52)
		)
		(stroke
			(width 0)
			(type default)
		)
	)
	(wire
		(pts
			(xy 264.16 160.02) (xy 281.305 160.02)
		)
		(stroke
			(width 0)
			(type default)
		)
	)
	(wire
		(pts
			(xy 148.59 116.84) (xy 148.59 119.38)
		)
		(stroke
			(width 0)
			(type default)
		)
	)
	(wire
		(pts
			(xy 119.38 124.46) (xy 119.38 231.775)
		)
		(stroke
			(width 0)
			(type default)
		)
	)
	(wire
		(pts
			(xy 241.3 106.68) (xy 225.425 106.68)
		)
		(stroke
			(width 0)
			(type default)
		)
	)
	(wire
		(pts
			(xy 145.415 215.9) (xy 152.4 215.9)
		)
		(stroke
			(width 0)
			(type default)
		)
	)
	(wire
		(pts
			(xy 145.415 91.44) (xy 148.59 91.44)
		)
		(stroke
			(width 0)
			(type default)
		)
	)
	(wire
		(pts
			(xy 148.59 109.22) (xy 148.59 111.76)
		)
		(stroke
			(width 0)
			(type default)
		)
	)
	(wire
		(pts
			(xy 241.3 160.02) (xy 225.425 160.02)
		)
		(stroke
			(width 0)
			(type default)
		)
	)
	(wire
		(pts
			(xy 264.16 144.78) (xy 281.305 144.78)
		)
		(stroke
			(width 0)
			(type default)
		)
	)
	(wire
		(pts
			(xy 145.415 213.36) (xy 152.4 213.36)
		)
		(stroke
			(width 0)
			(type default)
		)
	)
	(wire
		(pts
			(xy 122.555 81.28) (xy 119.38 81.28)
		)
		(stroke
			(width 0)
			(type default)
		)
	)
	(wire
		(pts
			(xy 145.415 78.74) (xy 148.59 78.74)
		)
		(stroke
			(width 0)
			(type default)
		)
	)
	(wire
		(pts
			(xy 241.3 114.3) (xy 225.425 114.3)
		)
		(stroke
			(width 0)
			(type default)
		)
	)
	(wire
		(pts
			(xy 265.43 132.08) (xy 265.43 152.4)
		)
		(stroke
			(width 0)
			(type default)
		)
	)
	(wire
		(pts
			(xy 122.555 190.5) (xy 113.665 190.5)
		)
		(stroke
			(width 0)
			(type default)
		)
	)
	(wire
		(pts
			(xy 241.3 111.76) (xy 225.425 111.76)
		)
		(stroke
			(width 0)
			(type default)
		)
	)
	(wire
		(pts
			(xy 145.415 96.52) (xy 148.59 96.52)
		)
		(stroke
			(width 0)
			(type default)
		)
	)
	(wire
		(pts
			(xy 119.38 93.98) (xy 119.38 96.52)
		)
		(stroke
			(width 0)
			(type default)
		)
	)
	(wire
		(pts
			(xy 148.59 106.68) (xy 148.59 109.22)
		)
		(stroke
			(width 0)
			(type default)
		)
	)
	(wire
		(pts
			(xy 239.395 147.32) (xy 239.395 167.64)
		)
		(stroke
			(width 0)
			(type default)
		)
	)
	(wire
		(pts
			(xy 241.3 165.1) (xy 225.425 165.1)
		)
		(stroke
			(width 0)
			(type default)
		)
	)
	(wire
		(pts
			(xy 113.665 185.42) (xy 113.665 182.88)
		)
		(stroke
			(width 0)
			(type default)
		)
	)
	(wire
		(pts
			(xy 119.38 104.14) (xy 119.38 106.68)
		)
		(stroke
			(width 0)
			(type default)
		)
	)
	(wire
		(pts
			(xy 148.59 66.04) (xy 148.59 68.58)
		)
		(stroke
			(width 0)
			(type default)
		)
	)
	(wire
		(pts
			(xy 119.38 83.82) (xy 119.38 86.36)
		)
		(stroke
			(width 0)
			(type default)
		)
	)
	(wire
		(pts
			(xy 145.415 86.36) (xy 148.59 86.36)
		)
		(stroke
			(width 0)
			(type default)
		)
	)
	(wire
		(pts
			(xy 122.555 114.3) (xy 119.38 114.3)
		)
		(stroke
			(width 0)
			(type default)
		)
	)
	(wire
		(pts
			(xy 119.38 109.22) (xy 119.38 111.76)
		)
		(stroke
			(width 0)
			(type default)
		)
	)
	(wire
		(pts
			(xy 148.59 114.3) (xy 148.59 116.84)
		)
		(stroke
			(width 0)
			(type default)
		)
	)
	(wire
		(pts
			(xy 122.555 193.04) (xy 113.665 193.04)
		)
		(stroke
			(width 0)
			(type default)
		)
	)
	(global_label "CA7"
		(shape bidirectional)
		(at 225.425 139.7 180)
		(fields_autoplaced yes)
		(effects
			(font
				(size 1.27 1.27)
			)
			(justify right)
		)
		(property "Intersheetrefs" "${INTERSHEET_REFS}"
			(at 0 0 0)
			(effects
				(font
					(size 1.27 1.27)
				)
				(hide yes)
			)
		)
	)
	(global_label "CA4"
		(shape bidirectional)
		(at 225.425 127 180)
		(fields_autoplaced yes)
		(effects
			(font
				(size 1.27 1.27)
			)
			(justify right)
		)
		(property "Intersheetrefs" "${INTERSHEET_REFS}"
			(at 0 0 0)
			(effects
				(font
					(size 1.27 1.27)
				)
				(hide yes)
			)
		)
	)
	(global_label "LBDQS"
		(shape output)
		(at 225.425 162.56 180)
		(fields_autoplaced yes)
		(effects
			(font
				(size 1.27 1.27)
			)
			(justify right)
		)
		(property "Intersheetrefs" "${INTERSHEET_REFS}"
			(at 0 0 0)
			(effects
				(font
					(size 1.27 1.27)
				)
				(hide yes)
			)
		)
	)
	(global_label "TEN"
		(shape output)
		(at 225.425 160.02 180)
		(fields_autoplaced yes)
		(effects
			(font
				(size 1.27 1.27)
			)
			(justify right)
		)
		(property "Intersheetrefs" "${INTERSHEET_REFS}"
			(at 0 0 0)
			(effects
				(font
					(size 1.27 1.27)
				)
				(hide yes)
			)
		)
	)
	(global_label "CA8"
		(shape bidirectional)
		(at 225.425 111.76 180)
		(fields_autoplaced yes)
		(effects
			(font
				(size 1.27 1.27)
			)
			(justify right)
		)
		(property "Intersheetrefs" "${INTERSHEET_REFS}"
			(at 0 0 0)
			(effects
				(font
					(size 1.27 1.27)
				)
				(hide yes)
			)
		)
	)
	(global_label "1V1_SYS"
		(shape output)
		(at 106.045 180.34 180)
		(fields_autoplaced yes)
		(effects
			(font
				(size 1.27 1.27)
			)
			(justify right)
		)
		(property "Intersheetrefs" "${INTERSHEET_REFS}"
			(at 2.54 0 0)
			(effects
				(font
					(size 1.27 1.27)
				)
				(hide yes)
			)
		)
	)
	(global_label "RESET_N"
		(shape output)
		(at 225.425 157.48 180)
		(fields_autoplaced yes)
		(effects
			(font
				(size 1.27 1.27)
			)
			(justify right)
		)
		(property "Intersheetrefs" "${INTERSHEET_REFS}"
			(at 0 0 0)
			(effects
				(font
					(size 1.27 1.27)
				)
				(hide yes)
			)
		)
	)
	(global_label "CA6"
		(shape bidirectional)
		(at 225.425 114.3 180)
		(fields_autoplaced yes)
		(effects
			(font
				(size 1.27 1.27)
			)
			(justify right)
		)
		(property "Intersheetrefs" "${INTERSHEET_REFS}"
			(at 0 0 0)
			(effects
				(font
					(size 1.27 1.27)
				)
				(hide yes)
			)
		)
	)
	(global_label "CA3"
		(shape bidirectional)
		(at 225.425 142.24 180)
		(fields_autoplaced yes)
		(effects
			(font
				(size 1.27 1.27)
			)
			(justify right)
		)
		(property "Intersheetrefs" "${INTERSHEET_REFS}"
			(at 0 0 0)
			(effects
				(font
					(size 1.27 1.27)
				)
				(hide yes)
			)
		)
	)
	(global_label "DQ1"
		(shape bidirectional)
		(at 281.305 142.24 0)
		(fields_autoplaced yes)
		(effects
			(font
				(size 1.27 1.27)
			)
			(justify left)
		)
		(property "Intersheetrefs" "${INTERSHEET_REFS}"
			(at -2.54 0 0)
			(effects
				(font
					(size 1.27 1.27)
				)
				(hide yes)
			)
		)
	)
	(global_label "SDA"
		(shape bidirectional)
		(at 107.315 223.52 180)
		(fields_autoplaced yes)
		(effects
			(font
				(size 1.27 1.27)
			)
			(justify right)
		)
		(property "Intersheetrefs" "${INTERSHEET_REFS}"
			(at 3.81 0 0)
			(effects
				(font
					(size 1.27 1.27)
				)
				(hide yes)
			)
		)
	)
	(global_label "DQ7"
		(shape bidirectional)
		(at 281.305 129.54 0)
		(fields_autoplaced yes)
		(effects
			(font
				(size 1.27 1.27)
			)
			(justify left)
		)
		(property "Intersheetrefs" "${INTERSHEET_REFS}"
			(at -2.54 0 0)
			(effects
				(font
					(size 1.27 1.27)
				)
				(hide yes)
			)
		)
	)
	(global_label "SCL"
		(shape output)
		(at 107.315 226.06 180)
		(fields_autoplaced yes)
		(effects
			(font
				(size 1.27 1.27)
			)
			(justify right)
		)
		(property "Intersheetrefs" "${INTERSHEET_REFS}"
			(at 3.81 0 0)
			(effects
				(font
					(size 1.27 1.27)
				)
				(hide yes)
			)
		)
	)
	(global_label "DQ5"
		(shape bidirectional)
		(at 281.305 127 0)
		(fields_autoplaced yes)
		(effects
			(font
				(size 1.27 1.27)
			)
			(justify left)
		)
		(property "Intersheetrefs" "${INTERSHEET_REFS}"
			(at -2.54 0 0)
			(effects
				(font
					(size 1.27 1.27)
				)
				(hide yes)
			)
		)
	)
	(global_label "CA0"
		(shape bidirectional)
		(at 225.425 129.54 180)
		(fields_autoplaced yes)
		(effects
			(font
				(size 1.27 1.27)
			)
			(justify right)
		)
		(property "Intersheetrefs" "${INTERSHEET_REFS}"
			(at 0 0 0)
			(effects
				(font
					(size 1.27 1.27)
				)
				(hide yes)
			)
		)
	)
	(global_label "TDQS_N"
		(shape output)
		(at 281.305 106.68 0)
		(fields_autoplaced yes)
		(effects
			(font
				(size 1.27 1.27)
			)
			(justify left)
		)
		(property "Intersheetrefs" "${INTERSHEET_REFS}"
			(at -2.54 0 0)
			(effects
				(font
					(size 1.27 1.27)
				)
				(hide yes)
			)
		)
	)
	(global_label "1V8_SYS"
		(shape output)
		(at 157.48 208.28 0)
		(fields_autoplaced yes)
		(effects
			(font
				(size 1.27 1.27)
			)
			(justify left)
		)
		(property "Intersheetrefs" "${INTERSHEET_REFS}"
			(at 0 0 0)
			(effects
				(font
					(size 1.27 1.27)
				)
				(hide yes)
			)
		)
	)
	(global_label "DQ2"
		(shape bidirectional)
		(at 281.305 147.32 0)
		(fields_autoplaced yes)
		(effects
			(font
				(size 1.27 1.27)
			)
			(justify left)
		)
		(property "Intersheetrefs" "${INTERSHEET_REFS}"
			(at -2.54 0 0)
			(effects
				(font
					(size 1.27 1.27)
				)
				(hide yes)
			)
		)
	)
	(global_label "CA11"
		(shape bidirectional)
		(at 225.425 132.08 180)
		(fields_autoplaced yes)
		(effects
			(font
				(size 1.27 1.27)
			)
			(justify right)
		)
		(property "Intersheetrefs" "${INTERSHEET_REFS}"
			(at 0 0 0)
			(effects
				(font
					(size 1.27 1.27)
				)
				(hide yes)
			)
		)
	)
	(global_label "CA1"
		(shape bidirectional)
		(at 225.425 149.86 180)
		(fields_autoplaced yes)
		(effects
			(font
				(size 1.27 1.27)
			)
			(justify right)
		)
		(property "Intersheetrefs" "${INTERSHEET_REFS}"
			(at 0 0 0)
			(effects
				(font
					(size 1.27 1.27)
				)
				(hide yes)
			)
		)
	)
	(global_label "CA5"
		(shape bidirectional)
		(at 225.425 144.78 180)
		(fields_autoplaced yes)
		(effects
			(font
				(size 1.27 1.27)
			)
			(justify right)
		)
		(property "Intersheetrefs" "${INTERSHEET_REFS}"
			(at 0 0 0)
			(effects
				(font
					(size 1.27 1.27)
				)
				(hide yes)
			)
		)
	)
	(global_label "CA2"
		(shape bidirectional)
		(at 225.425 116.84 180)
		(fields_autoplaced yes)
		(effects
			(font
				(size 1.27 1.27)
			)
			(justify right)
		)
		(property "Intersheetrefs" "${INTERSHEET_REFS}"
			(at 0 0 0)
			(effects
				(font
					(size 1.27 1.27)
				)
				(hide yes)
			)
		)
	)
	(global_label "DQS_N"
		(shape bidirectional)
		(at 225.425 152.4 180)
		(fields_autoplaced yes)
		(effects
			(font
				(size 1.27 1.27)
			)
			(justify right)
		)
		(property "Intersheetrefs" "${INTERSHEET_REFS}"
			(at 0 0 0)
			(effects
				(font
					(size 1.27 1.27)
				)
				(hide yes)
			)
		)
	)
	(global_label "CA12"
		(shape bidirectional)
		(at 225.425 106.68 180)
		(fields_autoplaced yes)
		(effects
			(font
				(size 1.27 1.27)
			)
			(justify right)
		)
		(property "Intersheetrefs" "${INTERSHEET_REFS}"
			(at 0 0 0)
			(effects
				(font
					(size 1.27 1.27)
				)
				(hide yes)
			)
		)
	)
	(global_label "DQ6"
		(shape bidirectional)
		(at 281.305 124.46 0)
		(fields_autoplaced yes)
		(effects
			(font
				(size 1.27 1.27)
			)
			(justify left)
		)
		(property "Intersheetrefs" "${INTERSHEET_REFS}"
			(at -2.54 0 0)
			(effects
				(font
					(size 1.27 1.27)
				)
				(hide yes)
			)
		)
	)
	(global_label "DQS_P"
		(shape bidirectional)
		(at 225.425 154.94 180)
		(fields_autoplaced yes)
		(effects
			(font
				(size 1.27 1.27)
			)
			(justify right)
		)
		(property "Intersheetrefs" "${INTERSHEET_REFS}"
			(at 0 0 0)
			(effects
				(font
					(size 1.27 1.27)
				)
				(hide yes)
			)
		)
	)
	(global_label "CA13"
		(shape bidirectional)
		(at 225.425 134.62 180)
		(fields_autoplaced yes)
		(effects
			(font
				(size 1.27 1.27)
			)
			(justify right)
		)
		(property "Intersheetrefs" "${INTERSHEET_REFS}"
			(at 0 0 0)
			(effects
				(font
					(size 1.27 1.27)
				)
				(hide yes)
			)
		)
	)
	(global_label "CS_N"
		(shape output)
		(at 281.305 104.14 0)
		(fields_autoplaced yes)
		(effects
			(font
				(size 1.27 1.27)
			)
			(justify left)
		)
		(property "Intersheetrefs" "${INTERSHEET_REFS}"
			(at -2.54 0 0)
			(effects
				(font
					(size 1.27 1.27)
				)
				(hide yes)
			)
		)
	)
	(global_label "ALERT_N"
		(shape bidirectional)
		(at 281.305 99.06 0)
		(fields_autoplaced yes)
		(effects
			(font
				(size 1.27 1.27)
			)
			(justify left)
		)
		(property "Intersheetrefs" "${INTERSHEET_REFS}"
			(at -2.54 0 0)
			(effects
				(font
					(size 1.27 1.27)
				)
				(hide yes)
			)
		)
	)
	(global_label "CLK_P"
		(shape output)
		(at 225.425 121.92 180)
		(fields_autoplaced yes)
		(effects
			(font
				(size 1.27 1.27)
			)
			(justify right)
		)
		(property "Intersheetrefs" "${INTERSHEET_REFS}"
			(at 0 0 0)
			(effects
				(font
					(size 1.27 1.27)
				)
				(hide yes)
			)
		)
	)
	(global_label "DQ4"
		(shape bidirectional)
		(at 281.305 134.62 0)
		(fields_autoplaced yes)
		(effects
			(font
				(size 1.27 1.27)
			)
			(justify left)
		)
		(property "Intersheetrefs" "${INTERSHEET_REFS}"
			(at -2.54 0 0)
			(effects
				(font
					(size 1.27 1.27)
				)
				(hide yes)
			)
		)
	)
	(global_label "LBDQ"
		(shape output)
		(at 225.425 165.1 180)
		(fields_autoplaced yes)
		(effects
			(font
				(size 1.27 1.27)
			)
			(justify right)
		)
		(property "Intersheetrefs" "${INTERSHEET_REFS}"
			(at 0 0 0)
			(effects
				(font
					(size 1.27 1.27)
				)
				(hide yes)
			)
		)
	)
	(global_label "MIR"
		(shape output)
		(at 281.305 101.6 0)
		(fields_autoplaced yes)
		(effects
			(font
				(size 1.27 1.27)
			)
			(justify left)
		)
		(property "Intersheetrefs" "${INTERSHEET_REFS}"
			(at -2.54 0 0)
			(effects
				(font
					(size 1.27 1.27)
				)
				(hide yes)
			)
		)
	)
	(global_label "TDQS_P"
		(shape output)
		(at 281.305 109.22 0)
		(fields_autoplaced yes)
		(effects
			(font
				(size 1.27 1.27)
			)
			(justify left)
		)
		(property "Intersheetrefs" "${INTERSHEET_REFS}"
			(at -2.54 0 0)
			(effects
				(font
					(size 1.27 1.27)
				)
				(hide yes)
			)
		)
	)
	(global_label "CA10"
		(shape bidirectional)
		(at 225.425 109.22 180)
		(fields_autoplaced yes)
		(effects
			(font
				(size 1.27 1.27)
			)
			(justify right)
		)
		(property "Intersheetrefs" "${INTERSHEET_REFS}"
			(at 0 0 0)
			(effects
				(font
					(size 1.27 1.27)
				)
				(hide yes)
			)
		)
	)
	(global_label "DQ0"
		(shape bidirectional)
		(at 281.305 149.86 0)
		(fields_autoplaced yes)
		(effects
			(font
				(size 1.27 1.27)
			)
			(justify left)
		)
		(property "Intersheetrefs" "${INTERSHEET_REFS}"
			(at -2.54 0 0)
			(effects
				(font
					(size 1.27 1.27)
				)
				(hide yes)
			)
		)
	)
	(global_label "CAI"
		(shape output)
		(at 281.305 96.52 0)
		(fields_autoplaced yes)
		(effects
			(font
				(size 1.27 1.27)
			)
			(justify left)
		)
		(property "Intersheetrefs" "${INTERSHEET_REFS}"
			(at -2.54 0 0)
			(effects
				(font
					(size 1.27 1.27)
				)
				(hide yes)
			)
		)
	)
	(global_label "DQ3"
		(shape bidirectional)
		(at 281.305 144.78 0)
		(fields_autoplaced yes)
		(effects
			(font
				(size 1.27 1.27)
			)
			(justify left)
		)
		(property "Intersheetrefs" "${INTERSHEET_REFS}"
			(at -2.54 0 0)
			(effects
				(font
					(size 1.27 1.27)
				)
				(hide yes)
			)
		)
	)
	(global_label "CLK_N"
		(shape output)
		(at 225.425 119.38 180)
		(fields_autoplaced yes)
		(effects
			(font
				(size 1.27 1.27)
			)
			(justify right)
		)
		(property "Intersheetrefs" "${INTERSHEET_REFS}"
			(at 0 0 0)
			(effects
				(font
					(size 1.27 1.27)
				)
				(hide yes)
			)
		)
	)
	(global_label "CA9"
		(shape bidirectional)
		(at 225.425 137.16 180)
		(fields_autoplaced yes)
		(effects
			(font
				(size 1.27 1.27)
			)
			(justify right)
		)
		(property "Intersheetrefs" "${INTERSHEET_REFS}"
			(at 0 0 0)
			(effects
				(font
					(size 1.27 1.27)
				)
				(hide yes)
			)
		)
	)
	(global_label "OTD_CA_A"
		(shape output)
		(at 281.305 160.02 0)
		(fields_autoplaced yes)
		(effects
			(font
				(size 1.27 1.27)
			)
			(justify left)
		)
		(property "Intersheetrefs" "${INTERSHEET_REFS}"
			(at -2.54 0 0)
			(effects
				(font
					(size 1.27 1.27)
				)
				(hide yes)
			)
		)
	)
	(symbol
		(lib_id "antmicropower:GND")
		(at 148.59 231.775 0)
		(unit 1)
		(exclude_from_sim no)
		(in_bom yes)
		(on_board yes)
		(dnp no)
		(property "Reference" "#PWR0101"
			(at 148.59 238.125 0)
			(effects
				(font
					(size 1.27 1.27)
				)
				(hide yes)
			)
		)
		(property "Value" "GND"
			(at 148.59 235.585 0)
			(effects
				(font
					(size 1.27 1.27)
				)
			)
		)
		(property "Footprint" ""
			(at 148.59 231.775 0)
			(effects
				(font
					(size 1.27 1.27)
				)
				(hide yes)
			)
		)
		(property "Datasheet" ""
			(at 148.59 231.775 0)
			(effects
				(font
					(size 1.27 1.27)
				)
				(hide yes)
			)
		)
		(property "Description" ""
			(at 148.59 231.775 0)
			(effects
				(font
					(size 1.27 1.27)
				)
			)
		)
		(pin "1"
		)
		(instances
			(project "ddr5-testbed"
				(path ""
					(reference "#PWR0101")
					(unit 1)
				)
			)
		)
	)
	(symbol
		(lib_id "antmicropower:GND")
		(at 119.38 231.775 0)
		(unit 1)
		(exclude_from_sim no)
		(in_bom yes)
		(on_board yes)
		(dnp no)
		(property "Reference" "#PWR0103"
			(at 119.38 238.125 0)
			(effects
				(font
					(size 1.27 1.27)
				)
				(hide yes)
			)
		)
		(property "Value" "GND"
			(at 119.38 235.585 0)
			(effects
				(font
					(size 1.27 1.27)
				)
			)
		)
		(property "Footprint" ""
			(at 119.38 231.775 0)
			(effects
				(font
					(size 1.27 1.27)
				)
				(hide yes)
			)
		)
		(property "Datasheet" ""
			(at 119.38 231.775 0)
			(effects
				(font
					(size 1.27 1.27)
				)
				(hide yes)
			)
		)
		(property "Description" ""
			(at 119.38 231.775 0)
			(effects
				(font
					(size 1.27 1.27)
				)
			)
		)
		(pin "1"
		)
		(instances
			(project "ddr5-testbed"
				(path ""
					(reference "#PWR0103")
					(unit 1)
				)
			)
		)
	)
	(symbol
		(lib_id "antmicropower:GND")
		(at 239.395 231.775 0)
		(unit 1)
		(exclude_from_sim no)
		(in_bom yes)
		(on_board yes)
		(dnp no)
		(property "Reference" "#PWR0102"
			(at 239.395 238.125 0)
			(effects
				(font
					(size 1.27 1.27)
				)
				(hide yes)
			)
		)
		(property "Value" "GND"
			(at 239.395 235.585 0)
			(effects
				(font
					(size 1.27 1.27)
				)
			)
		)
		(property "Footprint" ""
			(at 239.395 231.775 0)
			(effects
				(font
					(size 1.27 1.27)
				)
				(hide yes)
			)
		)
		(property "Datasheet" ""
			(at 239.395 231.775 0)
			(effects
				(font
					(size 1.27 1.27)
				)
				(hide yes)
			)
		)
		(property "Description" ""
			(at 239.395 231.775 0)
			(effects
				(font
					(size 1.27 1.27)
				)
			)
		)
		(pin "1"
		)
		(instances
			(project "ddr5-testbed"
				(path ""
					(reference "#PWR0102")
					(unit 1)
				)
			)
		)
	)
	(symbol
		(lib_id "antmicropower:GND")
		(at 265.43 231.775 0)
		(unit 1)
		(exclude_from_sim no)
		(in_bom yes)
		(on_board yes)
		(dnp no)
		(property "Reference" "#PWR0104"
			(at 265.43 238.125 0)
			(effects
				(font
					(size 1.27 1.27)
				)
				(hide yes)
			)
		)
		(property "Value" "GND"
			(at 265.43 235.585 0)
			(effects
				(font
					(size 1.27 1.27)
				)
			)
		)
		(property "Footprint" ""
			(at 265.43 231.775 0)
			(effects
				(font
					(size 1.27 1.27)
				)
				(hide yes)
			)
		)
		(property "Datasheet" ""
			(at 265.43 231.775 0)
			(effects
				(font
					(size 1.27 1.27)
				)
				(hide yes)
			)
		)
		(property "Description" ""
			(at 265.43 231.775 0)
			(effects
				(font
					(size 1.27 1.27)
				)
			)
		)
		(pin "1"
		)
		(instances
			(project "ddr5-testbed"
				(path ""
					(reference "#PWR0104")
					(unit 1)
				)
			)
		)
	)
	(symbol
		(lib_id "antmicroEdgeConnectors:PCB-Edge_SODIMM_2x130_DDR4")
		(at 122.555 63.5 0)
		(unit 1)
		(exclude_from_sim no)
		(in_bom no)
		(on_board yes)
		(dnp no)
		(fields_autoplaced yes)
		(property "Reference" "J1"
			(at 133.985 55.88 0)
			(effects
				(font
					(size 1.27 1.27)
					(thickness 0.15)
				)
			)
		)
		(property "Value" "PCB-Edge_SODIMM_2x130_DDR4"
			(at 133.985 58.42 0)
			(effects
				(font
					(size 1.27 1.27)
					(thickness 0.15)
				)
			)
		)
		(property "Footprint" "antmicro-footprints:PCB-Edge_SODIMM_2x130_DDR4"
			(at 159.385 68.58 0)
			(effects
				(font
					(size 1.27 1.27)
					(thickness 0.15)
				)
				(justify left bottom)
				(hide yes)
			)
		)
		(property "Datasheet" ""
			(at 159.385 76.2 0)
			(effects
				(font
					(size 1.27 1.27)
					(thickness 0.15)
				)
				(justify left bottom)
				(hide yes)
			)
		)
		(property "Description" ""
			(at 122.555 63.5 0)
			(effects
				(font
					(size 1.27 1.27)
				)
			)
		)
		(property "MPN" ""
			(at 159.385 69.85 0)
			(effects
				(font
					(size 1.27 1.27)
				)
				(justify left)
				(hide yes)
			)
		)
		(property "Manufacturer" ""
			(at 159.385 72.39 0)
			(effects
				(font
					(size 1.27 1.27)
				)
				(justify left)
				(hide yes)
			)
		)
		(property "Author" "Antmicro"
			(at 159.385 78.74 0)
			(effects
				(font
					(size 1.27 1.27)
					(thickness 0.15)
				)
				(justify left bottom)
				(hide yes)
			)
		)
		(property "License" "Apache-2.0"
			(at 159.385 81.28 0)
			(effects
				(font
					(size 1.27 1.27)
					(thickness 0.15)
				)
				(justify left bottom)
				(hide yes)
			)
		)
		(property "Public" "False"
			(at 159.385 83.82 0)
			(effects
				(font
					(size 1.27 1.27)
				)
				(justify left bottom)
				(hide yes)
			)
		)
		(pin "80"
		)
		(pin "113"
		)
		(pin "72"
		)
		(pin "254"
		)
		(pin "124"
		)
		(pin "74"
		)
		(pin "95"
		)
		(pin "26"
		)
		(pin "122"
		)
		(pin "162"
		)
		(pin "28"
		)
		(pin "159"
		)
		(pin "79"
		)
		(pin "29"
		)
		(pin "33"
		)
		(pin "161"
		)
		(pin "241"
		)
		(pin "204"
		)
		(pin "153"
		)
		(pin "126"
		)
		(pin "221"
		)
		(pin "227"
		)
		(pin "38"
		)
		(pin "58"
		)
		(pin "209"
		)
		(pin "142"
		)
		(pin "85"
		)
		(pin "242"
		)
		(pin "46"
		)
		(pin "57"
		)
		(pin "60"
		)
		(pin "40"
		)
		(pin "71"
		)
		(pin "229"
		)
		(pin "90"
		)
		(pin "231"
		)
		(pin "146"
		)
		(pin "160"
		)
		(pin "240"
		)
		(pin "245"
		)
		(pin "226"
		)
		(pin "232"
		)
		(pin "224"
		)
		(pin "244"
		)
		(pin "6"
		)
		(pin "211"
		)
		(pin "228"
		)
		(pin "235"
		)
		(pin "87"
		)
		(pin "70"
		)
		(pin "15"
		)
		(pin "255"
		)
		(pin "61"
		)
		(pin "155"
		)
		(pin "147"
		)
		(pin "105"
		)
		(pin "37"
		)
		(pin "149"
		)
		(pin "144"
		)
		(pin "9"
		)
		(pin "66"
		)
		(pin "125"
		)
		(pin "111"
		)
		(pin "145"
		)
		(pin "133"
		)
		(pin "163"
		)
		(pin "140"
		)
		(pin "141"
		)
		(pin "131"
		)
		(pin "77"
		)
		(pin "82"
		)
		(pin "51"
		)
		(pin "39"
		)
		(pin "212"
		)
		(pin "138"
		)
		(pin "208"
		)
		(pin "243"
		)
		(pin "44"
		)
		(pin "251"
		)
		(pin "218"
		)
		(pin "246"
		)
		(pin "27"
		)
		(pin "250"
		)
		(pin "248"
		)
		(pin "53"
		)
		(pin "101"
		)
		(pin "43"
		)
		(pin "171"
		)
		(pin "188"
		)
		(pin "215"
		)
		(pin "201"
		)
		(pin "165"
		)
		(pin "135"
		)
		(pin "194"
		)
		(pin "258"
		)
		(pin "259"
		)
		(pin "96"
		)
		(pin "10"
		)
		(pin "219"
		)
		(pin "116"
		)
		(pin "158"
		)
		(pin "130"
		)
		(pin "223"
		)
		(pin "68"
		)
		(pin "157"
		)
		(pin "214"
		)
		(pin "106"
		)
		(pin "78"
		)
		(pin "207"
		)
		(pin "20"
		)
		(pin "84"
		)
		(pin "139"
		)
		(pin "2"
		)
		(pin "143"
		)
		(pin "76"
		)
		(pin "93"
		)
		(pin "151"
		)
		(pin "156"
		)
		(pin "31"
		)
		(pin "41"
		)
		(pin "56"
		)
		(pin "22"
		)
		(pin "13"
		)
		(pin "253"
		)
		(pin "136"
		)
		(pin "234"
		)
		(pin "233"
		)
		(pin "150"
		)
		(pin "88"
		)
		(pin "30"
		)
		(pin "16"
		)
		(pin "117"
		)
		(pin "220"
		)
		(pin "121"
		)
		(pin "114"
		)
		(pin "119"
		)
		(pin "3"
		)
		(pin "99"
		)
		(pin "7"
		)
		(pin "123"
		)
		(pin "48"
		)
		(pin "89"
		)
		(pin "73"
		)
		(pin "210"
		)
		(pin "98"
		)
		(pin "25"
		)
		(pin "8"
		)
		(pin "148"
		)
		(pin "45"
		)
		(pin "69"
		)
		(pin "59"
		)
		(pin "67"
		)
		(pin "104"
		)
		(pin "115"
		)
		(pin "36"
		)
		(pin "92"
		)
		(pin "230"
		)
		(pin "120"
		)
		(pin "1"
		)
		(pin "100"
		)
		(pin "4"
		)
		(pin "134"
		)
		(pin "34"
		)
		(pin "247"
		)
		(pin "257"
		)
		(pin "249"
		)
		(pin "222"
		)
		(pin "256"
		)
		(pin "5"
		)
		(pin "49"
		)
		(pin "17"
		)
		(pin "236"
		)
		(pin "91"
		)
		(pin "14"
		)
		(pin "252"
		)
		(pin "217"
		)
		(pin "62"
		)
		(pin "213"
		)
		(pin "81"
		)
		(pin "18"
		)
		(pin "132"
		)
		(pin "260"
		)
		(pin "97"
		)
		(pin "175"
		)
		(pin "174"
		)
		(pin "195"
		)
		(pin "198"
		)
		(pin "11"
		)
		(pin "164"
		)
		(pin "118"
		)
		(pin "190"
		)
		(pin "203"
		)
		(pin "110"
		)
		(pin "178"
		)
		(pin "182"
		)
		(pin "197"
		)
		(pin "205"
		)
		(pin "184"
		)
		(pin "168"
		)
		(pin "128"
		)
		(pin "191"
		)
		(pin "185"
		)
		(pin "187"
		)
		(pin "196"
		)
		(pin "179"
		)
		(pin "47"
		)
		(pin "216"
		)
		(pin "86"
		)
		(pin "137"
		)
		(pin "12"
		)
		(pin "42"
		)
		(pin "186"
		)
		(pin "225"
		)
		(pin "54"
		)
		(pin "127"
		)
		(pin "24"
		)
		(pin "177"
		)
		(pin "239"
		)
		(pin "129"
		)
		(pin "52"
		)
		(pin "21"
		)
		(pin "103"
		)
		(pin "238"
		)
		(pin "35"
		)
		(pin "102"
		)
		(pin "64"
		)
		(pin "108"
		)
		(pin "94"
		)
		(pin "19"
		)
		(pin "50"
		)
		(pin "172"
		)
		(pin "200"
		)
		(pin "23"
		)
		(pin "180"
		)
		(pin "63"
		)
		(pin "192"
		)
		(pin "173"
		)
		(pin "189"
		)
		(pin "199"
		)
		(pin "237"
		)
		(pin "152"
		)
		(pin "32"
		)
		(pin "83"
		)
		(pin "65"
		)
		(pin "112"
		)
		(pin "107"
		)
		(pin "55"
		)
		(pin "169"
		)
		(pin "202"
		)
		(pin "183"
		)
		(pin "166"
		)
		(pin "109"
		)
		(pin "181"
		)
		(pin "193"
		)
		(pin "167"
		)
		(pin "206"
		)
		(pin "170"
		)
		(pin "176"
		)
		(pin "75"
		)
		(pin "154"
		)
		(instances
			(project "ddr5-testbed"
				(path ""
					(reference "J1")
					(unit 1)
				)
			)
		)
	)
	(symbol
		(lib_id "antmicroEdgeConnectors:PCB-Edge_SODIMM_2x130_DDR4")
		(at 241.3 66.04 0)
		(unit 2)
		(exclude_from_sim no)
		(in_bom no)
		(on_board yes)
		(dnp no)
		(fields_autoplaced yes)
		(property "Reference" "J1"
			(at 252.73 58.42 0)
			(effects
				(font
					(size 1.27 1.27)
					(thickness 0.15)
				)
			)
		)
		(property "Value" "PCB-Edge_SODIMM_2x130_DDR4"
			(at 252.73 60.96 0)
			(effects
				(font
					(size 1.27 1.27)
					(thickness 0.15)
				)
			)
		)
		(property "Footprint" "antmicro-footprints:PCB-Edge_SODIMM_2x130_DDR4"
			(at 278.13 71.12 0)
			(effects
				(font
					(size 1.27 1.27)
					(thickness 0.15)
				)
				(justify left bottom)
				(hide yes)
			)
		)
		(property "Datasheet" ""
			(at 278.13 78.74 0)
			(effects
				(font
					(size 1.27 1.27)
					(thickness 0.15)
				)
				(justify left bottom)
				(hide yes)
			)
		)
		(property "Description" ""
			(at 241.3 66.04 0)
			(effects
				(font
					(size 1.27 1.27)
				)
			)
		)
		(property "MPN" ""
			(at 278.13 72.39 0)
			(effects
				(font
					(size 1.27 1.27)
				)
				(justify left)
				(hide yes)
			)
		)
		(property "Manufacturer" ""
			(at 278.13 74.93 0)
			(effects
				(font
					(size 1.27 1.27)
				)
				(justify left)
				(hide yes)
			)
		)
		(property "Author" "Antmicro"
			(at 278.13 81.28 0)
			(effects
				(font
					(size 1.27 1.27)
					(thickness 0.15)
				)
				(justify left bottom)
				(hide yes)
			)
		)
		(property "License" "Apache-2.0"
			(at 278.13 83.82 0)
			(effects
				(font
					(size 1.27 1.27)
					(thickness 0.15)
				)
				(justify left bottom)
				(hide yes)
			)
		)
		(property "Public" "False"
			(at 278.13 86.36 0)
			(effects
				(font
					(size 1.27 1.27)
				)
				(justify left bottom)
				(hide yes)
			)
		)
		(pin "80"
		)
		(pin "113"
		)
		(pin "72"
		)
		(pin "254"
		)
		(pin "124"
		)
		(pin "74"
		)
		(pin "95"
		)
		(pin "26"
		)
		(pin "122"
		)
		(pin "162"
		)
		(pin "28"
		)
		(pin "159"
		)
		(pin "79"
		)
		(pin "29"
		)
		(pin "33"
		)
		(pin "161"
		)
		(pin "241"
		)
		(pin "204"
		)
		(pin "153"
		)
		(pin "126"
		)
		(pin "221"
		)
		(pin "227"
		)
		(pin "38"
		)
		(pin "58"
		)
		(pin "209"
		)
		(pin "142"
		)
		(pin "85"
		)
		(pin "242"
		)
		(pin "46"
		)
		(pin "57"
		)
		(pin "60"
		)
		(pin "40"
		)
		(pin "71"
		)
		(pin "229"
		)
		(pin "90"
		)
		(pin "231"
		)
		(pin "146"
		)
		(pin "160"
		)
		(pin "240"
		)
		(pin "245"
		)
		(pin "226"
		)
		(pin "232"
		)
		(pin "224"
		)
		(pin "244"
		)
		(pin "6"
		)
		(pin "211"
		)
		(pin "228"
		)
		(pin "235"
		)
		(pin "87"
		)
		(pin "70"
		)
		(pin "15"
		)
		(pin "255"
		)
		(pin "61"
		)
		(pin "155"
		)
		(pin "147"
		)
		(pin "105"
		)
		(pin "37"
		)
		(pin "149"
		)
		(pin "144"
		)
		(pin "9"
		)
		(pin "66"
		)
		(pin "125"
		)
		(pin "111"
		)
		(pin "145"
		)
		(pin "133"
		)
		(pin "163"
		)
		(pin "140"
		)
		(pin "141"
		)
		(pin "131"
		)
		(pin "77"
		)
		(pin "82"
		)
		(pin "51"
		)
		(pin "39"
		)
		(pin "212"
		)
		(pin "138"
		)
		(pin "208"
		)
		(pin "243"
		)
		(pin "44"
		)
		(pin "251"
		)
		(pin "218"
		)
		(pin "246"
		)
		(pin "27"
		)
		(pin "250"
		)
		(pin "248"
		)
		(pin "53"
		)
		(pin "101"
		)
		(pin "43"
		)
		(pin "171"
		)
		(pin "188"
		)
		(pin "215"
		)
		(pin "201"
		)
		(pin "165"
		)
		(pin "135"
		)
		(pin "194"
		)
		(pin "258"
		)
		(pin "259"
		)
		(pin "96"
		)
		(pin "10"
		)
		(pin "219"
		)
		(pin "116"
		)
		(pin "158"
		)
		(pin "130"
		)
		(pin "223"
		)
		(pin "68"
		)
		(pin "157"
		)
		(pin "214"
		)
		(pin "106"
		)
		(pin "78"
		)
		(pin "207"
		)
		(pin "20"
		)
		(pin "84"
		)
		(pin "139"
		)
		(pin "2"
		)
		(pin "143"
		)
		(pin "76"
		)
		(pin "93"
		)
		(pin "151"
		)
		(pin "156"
		)
		(pin "31"
		)
		(pin "41"
		)
		(pin "56"
		)
		(pin "22"
		)
		(pin "13"
		)
		(pin "253"
		)
		(pin "136"
		)
		(pin "234"
		)
		(pin "233"
		)
		(pin "150"
		)
		(pin "88"
		)
		(pin "30"
		)
		(pin "16"
		)
		(pin "117"
		)
		(pin "220"
		)
		(pin "121"
		)
		(pin "114"
		)
		(pin "119"
		)
		(pin "3"
		)
		(pin "99"
		)
		(pin "7"
		)
		(pin "123"
		)
		(pin "48"
		)
		(pin "89"
		)
		(pin "73"
		)
		(pin "210"
		)
		(pin "98"
		)
		(pin "25"
		)
		(pin "8"
		)
		(pin "148"
		)
		(pin "45"
		)
		(pin "69"
		)
		(pin "59"
		)
		(pin "67"
		)
		(pin "104"
		)
		(pin "115"
		)
		(pin "36"
		)
		(pin "92"
		)
		(pin "230"
		)
		(pin "120"
		)
		(pin "1"
		)
		(pin "100"
		)
		(pin "4"
		)
		(pin "134"
		)
		(pin "34"
		)
		(pin "247"
		)
		(pin "257"
		)
		(pin "249"
		)
		(pin "222"
		)
		(pin "256"
		)
		(pin "5"
		)
		(pin "49"
		)
		(pin "17"
		)
		(pin "236"
		)
		(pin "91"
		)
		(pin "14"
		)
		(pin "252"
		)
		(pin "217"
		)
		(pin "62"
		)
		(pin "213"
		)
		(pin "81"
		)
		(pin "18"
		)
		(pin "132"
		)
		(pin "260"
		)
		(pin "97"
		)
		(pin "175"
		)
		(pin "174"
		)
		(pin "195"
		)
		(pin "198"
		)
		(pin "11"
		)
		(pin "164"
		)
		(pin "118"
		)
		(pin "190"
		)
		(pin "203"
		)
		(pin "110"
		)
		(pin "178"
		)
		(pin "182"
		)
		(pin "197"
		)
		(pin "205"
		)
		(pin "184"
		)
		(pin "168"
		)
		(pin "128"
		)
		(pin "191"
		)
		(pin "185"
		)
		(pin "187"
		)
		(pin "196"
		)
		(pin "179"
		)
		(pin "47"
		)
		(pin "216"
		)
		(pin "86"
		)
		(pin "137"
		)
		(pin "12"
		)
		(pin "42"
		)
		(pin "186"
		)
		(pin "225"
		)
		(pin "54"
		)
		(pin "127"
		)
		(pin "24"
		)
		(pin "177"
		)
		(pin "239"
		)
		(pin "129"
		)
		(pin "52"
		)
		(pin "21"
		)
		(pin "103"
		)
		(pin "238"
		)
		(pin "35"
		)
		(pin "102"
		)
		(pin "64"
		)
		(pin "108"
		)
		(pin "94"
		)
		(pin "19"
		)
		(pin "50"
		)
		(pin "172"
		)
		(pin "200"
		)
		(pin "23"
		)
		(pin "180"
		)
		(pin "63"
		)
		(pin "192"
		)
		(pin "173"
		)
		(pin "189"
		)
		(pin "199"
		)
		(pin "237"
		)
		(pin "152"
		)
		(pin "32"
		)
		(pin "83"
		)
		(pin "65"
		)
		(pin "112"
		)
		(pin "107"
		)
		(pin "55"
		)
		(pin "169"
		)
		(pin "202"
		)
		(pin "183"
		)
		(pin "166"
		)
		(pin "109"
		)
		(pin "181"
		)
		(pin "193"
		)
		(pin "167"
		)
		(pin "206"
		)
		(pin "170"
		)
		(pin "176"
		)
		(pin "75"
		)
		(pin "154"
		)
		(instances
			(project "ddr5-testbed"
				(path ""
					(reference "J1")
					(unit 2)
				)
			)
		)
	)
)
